(kicad_pcb
	(version 20260206)
	(generator "pcbnew")
	(generator_version "10.0")
	(general
		(thickness 1.6)
		(legacy_teardrops no)
	)
	(paper "A4")
	(title_block
		(title "01162023_DA0F0TEBIF0_F0T_Expander_BD_F_brd_V02_OCP.brd")
		(comment 1 "Grand Teton / footprints 2110-2116 of 9728")
	)
	(layers
		(0 "F.Cu" signal "TOP")
		(4 "In1.Cu" signal "GND")
		(6 "In2.Cu" signal "VCC")
		(8 "In3.Cu" signal "VCC1")
		(10 "In4.Cu" signal "GND1")
		(12 "In5.Cu" signal "IN1")
		(14 "In6.Cu" signal "GND2")
		(16 "In7.Cu" signal "IN2")
		(18 "In8.Cu" signal "GND3")
		(20 "In9.Cu" signal "IN3")
		(22 "In10.Cu" signal "GND4")
		(24 "In11.Cu" signal "IN4")
		(26 "In12.Cu" signal "GND5")
		(28 "In13.Cu" signal "IN5")
		(30 "In14.Cu" signal "GND6")
		(32 "In15.Cu" signal "IN6")
		(34 "In16.Cu" signal "GND7")
		(2 "B.Cu" signal "BOTTOM")
		(9 "F.Adhes" user "F.Adhesive")
		(11 "B.Adhes" user "B.Adhesive")
		(13 "F.Paste" user "Package Geometry/Pastemask Top")
		(15 "B.Paste" user "Package Geometry/Pastemask Bottom")
		(5 "F.SilkS" user "Ref Des/Silkscreen Top")
		(7 "B.SilkS" user "Ref Des/Silkscreen Bottom")
		(1 "F.Mask" user "Board Geometry/Soldermask Top")
		(3 "B.Mask" user "Board Geometry/Soldermask Bottom")
		(17 "Dwgs.User" user "User.Drawings")
		(19 "Cmts.User" user "User.Comments")
		(21 "Eco1.User" user "User.Eco1")
		(23 "Eco2.User" user "User.Eco2")
		(25 "Edge.Cuts" user "Board Geometry/Outline")
		(27 "Margin" user)
		(31 "F.CrtYd" user "Package Geometry/Place Bound Top")
		(29 "B.CrtYd" user "Package Geometry/Place Bound Bottom")
		(35 "F.Fab" user "Ref Des/Assembly Top")
		(33 "B.Fab" user "Ref Des/Assembly Bottom")
	)
	(footprint ""
		(layer "F.Cu")
		(at 26.374344 -252.356874 -90)
		(property "Reference" "R1192"
			(at 0 0 270)
			(layer "F.SilkS")
			(hide yes)
			(effects
				(font
					(size 1.27 1.27)
				)
			)
		)
		(property "Value" ""
			(at 0 0 270)
			(layer "F.Fab")
			(effects
				(font
					(size 1.27 1.27)
				)
			)
		)
		(duplicate_pad_numbers_are_jumpers no)
		(fp_line
			(start -0.7874 0.4064)
			(end -0.7874 -0.4064)
			(stroke
				(width 0.1524)
				(type default)
			)
			(layer "F.SilkS")
		)
		(fp_line
			(start 0.7874 0.4064)
			(end -0.7874 0.4064)
			(stroke
				(width 0.1524)
				(type default)
			)
			(layer "F.SilkS")
		)
		(fp_line
			(start -0.7874 -0.4064)
			(end 0.7874 -0.4064)
			(stroke
				(width 0.1524)
				(type default)
			)
			(layer "F.SilkS")
		)
		(fp_line
			(start 0.7874 -0.4064)
			(end 0.7874 0.4064)
			(stroke
				(width 0.1524)
				(type default)
			)
			(layer "F.SilkS")
		)
		(fp_line
			(start -0.67945 0.3048)
			(end -0.67945 -0.305054)
			(stroke
				(width 0.1)
				(type default)
			)
			(layer "F.Fab")
		)
		(fp_line
			(start -0.12065 0.3048)
			(end -0.67945 0.3048)
			(stroke
				(width 0.1)
				(type default)
			)
			(layer "F.Fab")
		)
		(fp_line
			(start 0.120396 0.3048)
			(end 0.120396 0.2794)
			(stroke
				(width 0.1)
				(type default)
			)
			(layer "F.Fab")
		)
		(fp_line
			(start 0.67945 0.3048)
			(end 0.120396 0.3048)
			(stroke
				(width 0.1)
				(type default)
			)
			(layer "F.Fab")
		)
		(fp_line
			(start -0.12065 0.2794)
			(end -0.12065 0.3048)
			(stroke
				(width 0.1)
				(type default)
			)
			(layer "F.Fab")
		)
		(fp_line
			(start 0.120396 0.2794)
			(end -0.12065 0.2794)
			(stroke
				(width 0.1)
				(type default)
			)
			(layer "F.Fab")
		)
		(fp_line
			(start -0.12065 -0.2794)
			(end 0.12065 -0.2794)
			(stroke
				(width 0.1)
				(type default)
			)
			(layer "F.Fab")
		)
		(fp_line
			(start 0.12065 -0.2794)
			(end 0.12065 -0.3048)
			(stroke
				(width 0.1)
				(type default)
			)
			(layer "F.Fab")
		)
		(fp_line
			(start 0.12065 -0.3048)
			(end 0.67945 -0.3048)
			(stroke
				(width 0.1)
				(type default)
			)
			(layer "F.Fab")
		)
		(fp_line
			(start 0.67945 -0.3048)
			(end 0.67945 0.3048)
			(stroke
				(width 0.1)
				(type default)
			)
			(layer "F.Fab")
		)
		(fp_line
			(start -0.67945 -0.305054)
			(end -0.12065 -0.305054)
			(stroke
				(width 0.1)
				(type default)
			)
			(layer "F.Fab")
		)
		(fp_line
			(start -0.12065 -0.305054)
			(end -0.12065 -0.2794)
			(stroke
				(width 0.1)
				(type default)
			)
			(layer "F.Fab")
		)
		(pad "1" smd circle
			(at -0.40005 0 270)
			(size 0 0)
			(layers "F.Cu" "F.Mask" "F.Paste")
			(net "GND")
		)
		(pad "2" smd circle
			(at 0.40005 0 270)
			(size 0 0)
			(layers "F.Cu" "F.Mask" "F.Paste")
			(net "PEX0_MODE_SEL2")
		)
	)
	(footprint ""
		(layer "F.Cu")
		(at 327.533 -211.201)
		(property "Reference" "R4160"
			(at 0 0 0)
			(layer "F.SilkS")
			(hide yes)
			(effects
				(font
					(size 1.27 1.27)
				)
			)
		)
		(property "Value" ""
			(at 0 0 0)
			(layer "F.Fab")
			(effects
				(font
					(size 1.27 1.27)
				)
			)
		)
		(duplicate_pad_numbers_are_jumpers no)
		(fp_line
			(start -0.7874 -0.4064)
			(end 0.7874 -0.4064)
			(stroke
				(width 0.1524)
				(type default)
			)
			(layer "F.SilkS")
		)
		(fp_line
			(start -0.7874 0.4064)
			(end -0.7874 -0.4064)
			(stroke
				(width 0.1524)
				(type default)
			)
			(layer "F.SilkS")
		)
		(fp_line
			(start 0.7874 -0.4064)
			(end 0.7874 0.4064)
			(stroke
				(width 0.1524)
				(type default)
			)
			(layer "F.SilkS")
		)
		(fp_line
			(start 0.7874 0.4064)
			(end -0.7874 0.4064)
			(stroke
				(width 0.1524)
				(type default)
			)
			(layer "F.SilkS")
		)
		(fp_line
			(start -0.67945 -0.305054)
			(end -0.12065 -0.305054)
			(stroke
				(width 0.1)
				(type default)
			)
			(layer "F.Fab")
		)
		(fp_line
			(start -0.67945 0.3048)
			(end -0.67945 -0.305054)
			(stroke
				(width 0.1)
				(type default)
			)
			(layer "F.Fab")
		)
		(fp_line
			(start -0.12065 -0.305054)
			(end -0.12065 -0.2794)
			(stroke
				(width 0.1)
				(type default)
			)
			(layer "F.Fab")
		)
		(fp_line
			(start -0.12065 -0.2794)
			(end 0.12065 -0.2794)
			(stroke
				(width 0.1)
				(type default)
			)
			(layer "F.Fab")
		)
		(fp_line
			(start -0.12065 0.2794)
			(end -0.12065 0.3048)
			(stroke
				(width 0.1)
				(type default)
			)
			(layer "F.Fab")
		)
		(fp_line
			(start -0.12065 0.3048)
			(end -0.67945 0.3048)
			(stroke
				(width 0.1)
				(type default)
			)
			(layer "F.Fab")
		)
		(fp_line
			(start 0.120396 0.2794)
			(end -0.12065 0.2794)
			(stroke
				(width 0.1)
				(type default)
			)
			(layer "F.Fab")
		)
		(fp_line
			(start 0.120396 0.3048)
			(end 0.120396 0.2794)
			(stroke
				(width 0.1)
				(type default)
			)
			(layer "F.Fab")
		)
		(fp_line
			(start 0.12065 -0.3048)
			(end 0.67945 -0.3048)
			(stroke
				(width 0.1)
				(type default)
			)
			(layer "F.Fab")
		)
		(fp_line
			(start 0.12065 -0.2794)
			(end 0.12065 -0.3048)
			(stroke
				(width 0.1)
				(type default)
			)
			(layer "F.Fab")
		)
		(fp_line
			(start 0.67945 -0.3048)
			(end 0.67945 0.3048)
			(stroke
				(width 0.1)
				(type default)
			)
			(layer "F.Fab")
		)
		(fp_line
			(start 0.67945 0.3048)
			(end 0.120396 0.3048)
			(stroke
				(width 0.1)
				(type default)
			)
			(layer "F.Fab")
		)
		(pad "1" smd circle
			(at -0.40005 0)
			(size 0 0)
			(layers "F.Cu" "F.Mask" "F.Paste")
			(net "PRSNT_SSD13_FPGA_R_N")
		)
		(pad "2" smd circle
			(at 0.40005 0)
			(size 0 0)
			(layers "F.Cu" "F.Mask" "F.Paste")
			(net "PRSNT_SSD13_FPGA_N")
		)
	)
	(footprint ""
		(layer "F.Cu")
		(at 364.612936 -118.378986 90)
		(property "Reference" "PC910"
			(at 0 0 90)
			(layer "F.SilkS")
			(hide yes)
			(effects
				(font
					(size 1.27 1.27)
				)
			)
		)
		(property "Value" ""
			(at 0 0 90)
			(layer "F.Fab")
			(effects
				(font
					(size 1.27 1.27)
				)
			)
		)
		(duplicate_pad_numbers_are_jumpers no)
		(fp_line
			(start 0.7874 -0.4064)
			(end 0.7874 0.4064)
			(stroke
				(width 0.1524)
				(type default)
			)
			(layer "F.SilkS")
		)
		(fp_line
			(start -0.7874 -0.4064)
			(end 0.7874 -0.4064)
			(stroke
				(width 0.1524)
				(type default)
			)
			(layer "F.SilkS")
		)
		(fp_line
			(start 0.7874 0.4064)
			(end -0.7874 0.4064)
			(stroke
				(width 0.1524)
				(type default)
			)
			(layer "F.SilkS")
		)
		(fp_line
			(start -0.7874 0.4064)
			(end -0.7874 -0.4064)
			(stroke
				(width 0.1524)
				(type default)
			)
			(layer "F.SilkS")
		)
		(fp_line
			(start -0.12065 -0.305054)
			(end -0.12065 -0.2794)
			(stroke
				(width 0.1)
				(type default)
			)
			(layer "F.Fab")
		)
		(fp_line
			(start -0.67945 -0.305054)
			(end -0.12065 -0.305054)
			(stroke
				(width 0.1)
				(type default)
			)
			(layer "F.Fab")
		)
		(fp_line
			(start 0.67945 -0.3048)
			(end 0.67945 0.3048)
			(stroke
				(width 0.1)
				(type default)
			)
			(layer "F.Fab")
		)
		(fp_line
			(start 0.12065 -0.3048)
			(end 0.67945 -0.3048)
			(stroke
				(width 0.1)
				(type default)
			)
			(layer "F.Fab")
		)
		(fp_line
			(start 0.12065 -0.2794)
			(end 0.12065 -0.3048)
			(stroke
				(width 0.1)
				(type default)
			)
			(layer "F.Fab")
		)
		(fp_line
			(start -0.12065 -0.2794)
			(end 0.12065 -0.2794)
			(stroke
				(width 0.1)
				(type default)
			)
			(layer "F.Fab")
		)
		(fp_line
			(start 0.120396 0.2794)
			(end -0.12065 0.2794)
			(stroke
				(width 0.1)
				(type default)
			)
			(layer "F.Fab")
		)
		(fp_line
			(start -0.12065 0.2794)
			(end -0.12065 0.3048)
			(stroke
				(width 0.1)
				(type default)
			)
			(layer "F.Fab")
		)
		(fp_line
			(start 0.67945 0.3048)
			(end 0.120396 0.3048)
			(stroke
				(width 0.1)
				(type default)
			)
			(layer "F.Fab")
		)
		(fp_line
			(start 0.120396 0.3048)
			(end 0.120396 0.2794)
			(stroke
				(width 0.1)
				(type default)
			)
			(layer "F.Fab")
		)
		(fp_line
			(start -0.12065 0.3048)
			(end -0.67945 0.3048)
			(stroke
				(width 0.1)
				(type default)
			)
			(layer "F.Fab")
		)
		(fp_line
			(start -0.67945 0.3048)
			(end -0.67945 -0.305054)
			(stroke
				(width 0.1)
				(type default)
			)
			(layer "F.Fab")
		)
		(pad "1" smd circle
			(at -0.40005 0 90)
			(size 0 0)
			(layers "F.Cu" "F.Mask" "F.Paste")
			(net "P3V3_NIC6_CO_GATE")
		)
		(pad "2" smd circle
			(at 0.40005 0 90)
			(size 0 0)
			(layers "F.Cu" "F.Mask" "F.Paste")
			(net "GND")
		)
	)
	(footprint ""
		(layer "F.Cu")
		(at 82.661506 -148.91131 180)
		(property "Reference" "C9"
			(at 0 0 180)
			(layer "F.SilkS")
			(hide yes)
			(effects
				(font
					(size 1.27 1.27)
				)
			)
		)
		(property "Value" ""
			(at 0 0 180)
			(layer "F.Fab")
			(effects
				(font
					(size 1.27 1.27)
				)
			)
		)
		(duplicate_pad_numbers_are_jumpers no)
		(fp_line
			(start 0.299974 0.150114)
			(end -0.299974 0.150114)
			(stroke
				(width 0.1)
				(type default)
			)
			(layer "F.Fab")
		)
		(fp_line
			(start 0.299974 -0.150114)
			(end 0.299974 0.150114)
			(stroke
				(width 0.1)
				(type default)
			)
			(layer "F.Fab")
		)
		(fp_line
			(start -0.299974 0.150114)
			(end -0.299974 -0.150114)
			(stroke
				(width 0.1)
				(type default)
			)
			(layer "F.Fab")
		)
		(fp_line
			(start -0.299974 -0.150114)
			(end 0.299974 -0.150114)
			(stroke
				(width 0.1)
				(type default)
			)
			(layer "F.Fab")
		)
		(pad "1" smd rect
			(at -0.2667 0 180)
			(size 0.3048 0.381)
			(layers "F.Cu" "F.Mask" "F.Paste")
			(net "P5E_PEX0_STN0_TX_DP<11>")
		)
		(pad "2" smd rect
			(at 0.2667 0 180)
			(size 0.3048 0.381)
			(layers "F.Cu" "F.Mask" "F.Paste")
			(net "P5E_PEX0_STN0_TX_C_DP<11>")
		)
	)
	(footprint ""
		(layer "F.Cu")
		(at 239.754664 -206.51216 90)
		(property "Reference" "R4850"
			(at 0 0 90)
			(layer "F.SilkS")
			(hide yes)
			(effects
				(font
					(size 1.27 1.27)
				)
			)
		)
		(property "Value" ""
			(at 0 0 90)
			(layer "F.Fab")
			(effects
				(font
					(size 1.27 1.27)
				)
			)
		)
		(duplicate_pad_numbers_are_jumpers no)
		(fp_line
			(start 0.7874 -0.4064)
			(end 0.7874 0.4064)
			(stroke
				(width 0.1524)
				(type default)
			)
			(layer "F.SilkS")
		)
		(fp_line
			(start -0.7874 -0.4064)
			(end 0.7874 -0.4064)
			(stroke
				(width 0.1524)
				(type default)
			)
			(layer "F.SilkS")
		)
		(fp_line
			(start 0.7874 0.4064)
			(end -0.7874 0.4064)
			(stroke
				(width 0.1524)
				(type default)
			)
			(layer "F.SilkS")
		)
		(fp_line
			(start -0.7874 0.4064)
			(end -0.7874 -0.4064)
			(stroke
				(width 0.1524)
				(type default)
			)
			(layer "F.SilkS")
		)
		(fp_line
			(start -0.12065 -0.305054)
			(end -0.12065 -0.2794)
			(stroke
				(width 0.1)
				(type default)
			)
			(layer "F.Fab")
		)
		(fp_line
			(start -0.67945 -0.305054)
			(end -0.12065 -0.305054)
			(stroke
				(width 0.1)
				(type default)
			)
			(layer "F.Fab")
		)
		(fp_line
			(start 0.67945 -0.3048)
			(end 0.67945 0.3048)
			(stroke
				(width 0.1)
				(type default)
			)
			(layer "F.Fab")
		)
		(fp_line
			(start 0.12065 -0.3048)
			(end 0.67945 -0.3048)
			(stroke
				(width 0.1)
				(type default)
			)
			(layer "F.Fab")
		)
		(fp_line
			(start 0.12065 -0.2794)
			(end 0.12065 -0.3048)
			(stroke
				(width 0.1)
				(type default)
			)
			(layer "F.Fab")
		)
		(fp_line
			(start -0.12065 -0.2794)
			(end 0.12065 -0.2794)
			(stroke
				(width 0.1)
				(type default)
			)
			(layer "F.Fab")
		)
		(fp_line
			(start 0.120396 0.2794)
			(end -0.12065 0.2794)
			(stroke
				(width 0.1)
				(type default)
			)
			(layer "F.Fab")
		)
		(fp_line
			(start -0.12065 0.2794)
			(end -0.12065 0.3048)
			(stroke
				(width 0.1)
				(type default)
			)
			(layer "F.Fab")
		)
		(fp_line
			(start 0.67945 0.3048)
			(end 0.120396 0.3048)
			(stroke
				(width 0.1)
				(type default)
			)
			(layer "F.Fab")
		)
		(fp_line
			(start 0.120396 0.3048)
			(end 0.120396 0.2794)
			(stroke
				(width 0.1)
				(type default)
			)
			(layer "F.Fab")
		)
		(fp_line
			(start -0.12065 0.3048)
			(end -0.67945 0.3048)
			(stroke
				(width 0.1)
				(type default)
			)
			(layer "F.Fab")
		)
		(fp_line
			(start -0.67945 0.3048)
			(end -0.67945 -0.305054)
			(stroke
				(width 0.1)
				(type default)
			)
			(layer "F.Fab")
		)
		(pad "1" smd circle
			(at -0.40005 0 90)
			(size 0 0)
			(layers "F.Cu" "F.Mask" "F.Paste")
			(net "P12V_AUX")
		)
		(pad "2" smd circle
			(at 0.40005 0 90)
			(size 0 0)
			(layers "F.Cu" "F.Mask" "F.Paste")
			(net "P12V_AUX_SCALED")
		)
	)
	(footprint ""
		(layer "F.Cu")
		(at 358.013 -216.408 180)
		(property "Reference" "R4092"
			(at 0 0 180)
			(layer "F.SilkS")
			(hide yes)
			(effects
				(font
					(size 1.27 1.27)
				)
			)
		)
		(property "Value" ""
			(at 0 0 180)
			(layer "F.Fab")
			(effects
				(font
					(size 1.27 1.27)
				)
			)
		)
		(duplicate_pad_numbers_are_jumpers no)
		(fp_line
			(start 0.7874 0.4064)
			(end -0.7874 0.4064)
			(stroke
				(width 0.1524)
				(type default)
			)
			(layer "F.SilkS")
		)
		(fp_line
			(start 0.7874 -0.4064)
			(end 0.7874 0.4064)
			(stroke
				(width 0.1524)
				(type default)
			)
			(layer "F.SilkS")
		)
		(fp_line
			(start -0.7874 0.4064)
			(end -0.7874 -0.4064)
			(stroke
				(width 0.1524)
				(type default)
			)
			(layer "F.SilkS")
		)
		(fp_line
			(start -0.7874 -0.4064)
			(end 0.7874 -0.4064)
			(stroke
				(width 0.1524)
				(type default)
			)
			(layer "F.SilkS")
		)
		(fp_line
			(start 0.67945 0.3048)
			(end 0.120396 0.3048)
			(stroke
				(width 0.1)
				(type default)
			)
			(layer "F.Fab")
		)
		(fp_line
			(start 0.67945 -0.3048)
			(end 0.67945 0.3048)
			(stroke
				(width 0.1)
				(type default)
			)
			(layer "F.Fab")
		)
		(fp_line
			(start 0.12065 -0.2794)
			(end 0.12065 -0.3048)
			(stroke
				(width 0.1)
				(type default)
			)
			(layer "F.Fab")
		)
		(fp_line
			(start 0.12065 -0.3048)
			(end 0.67945 -0.3048)
			(stroke
				(width 0.1)
				(type default)
			)
			(layer "F.Fab")
		)
		(fp_line
			(start 0.120396 0.3048)
			(end 0.120396 0.2794)
			(stroke
				(width 0.1)
				(type default)
			)
			(layer "F.Fab")
		)
		(fp_line
			(start 0.120396 0.2794)
			(end -0.12065 0.2794)
			(stroke
				(width 0.1)
				(type default)
			)
			(layer "F.Fab")
		)
		(fp_line
			(start -0.12065 0.3048)
			(end -0.67945 0.3048)
			(stroke
				(width 0.1)
				(type default)
			)
			(layer "F.Fab")
		)
		(fp_line
			(start -0.12065 0.2794)
			(end -0.12065 0.3048)
			(stroke
				(width 0.1)
				(type default)
			)
			(layer "F.Fab")
		)
		(fp_line
			(start -0.12065 -0.2794)
			(end 0.12065 -0.2794)
			(stroke
				(width 0.1)
				(type default)
			)
			(layer "F.Fab")
		)
		(fp_line
			(start -0.12065 -0.305054)
			(end -0.12065 -0.2794)
			(stroke
				(width 0.1)
				(type default)
			)
			(layer "F.Fab")
		)
		(fp_line
			(start -0.67945 0.3048)
			(end -0.67945 -0.305054)
			(stroke
				(width 0.1)
				(type default)
			)
			(layer "F.Fab")
		)
		(fp_line
			(start -0.67945 -0.305054)
			(end -0.12065 -0.305054)
			(stroke
				(width 0.1)
				(type default)
			)
			(layer "F.Fab")
		)
		(pad "1" smd circle
			(at -0.40005 0 180)
			(size 0 0)
			(layers "F.Cu" "F.Mask" "F.Paste")
			(net "PRSNT_NIC0_FPGA_R_N")
		)
		(pad "2" smd circle
			(at 0.40005 0 180)
			(size 0 0)
			(layers "F.Cu" "F.Mask" "F.Paste")
			(net "PRSNT_NIC0_FPGA_N")
		)
	)
	(footprint ""
		(layer "F.Cu")
		(at 28.495244 -35.48253)
		(property "Reference" "U382"
			(at -2.535174 1.29413 90)
			(unlocked yes)
			(layer "F.SilkS")
			(effects
				(font
					(size 0.7874 0.5842)
					(thickness 0.1524)
				)
				(justify left)
			)
		)
		(property "Value" ""
			(at 0 0 0)
			(layer "F.Fab")
			(effects
				(font
					(size 1.27 1.27)
				)
			)
		)
		(duplicate_pad_numbers_are_jumpers no)
		(fp_line
			(start -1.3462 -1.1938)
			(end -1.3462 1.1684)
			(stroke
				(width 0.1524)
				(type default)
			)
			(layer "F.SilkS")
		)
		(fp_line
			(start -1.3462 1.1938)
			(end 1.3462 1.1938)
			(stroke
				(width 0.1524)
				(type default)
			)
			(layer "F.SilkS")
		)
		(fp_line
			(start 1.3462 -1.1938)
			(end -1.3462 -1.1938)
			(stroke
				(width 0.1524)
				(type default)
			)
			(layer "F.SilkS")
		)
		(fp_line
			(start 1.3462 1.1938)
			(end 1.3462 -1.1938)
			(stroke
				(width 0.1524)
				(type default)
			)
			(layer "F.SilkS")
		)
		(fp_poly
			(pts
				(xy -1.447038 -0.760476) (xy -2.052066 -0.457962) (xy -2.052066 -1.06299)
			)
			(stroke
				(width 0)
				(type default)
			)
			(fill yes)
			(layer "F.SilkS")
		)
		(fp_line
			(start -0.674878 -1.124966)
			(end -0.674878 1.124966)
			(stroke
				(width 0.1)
				(type default)
			)
			(layer "F.Fab")
		)
		(fp_line
			(start -0.674878 1.124966)
			(end 0.674878 1.124966)
			(stroke
				(width 0.1)
				(type default)
			)
			(layer "F.Fab")
		)
		(fp_line
			(start 0.674878 -1.124966)
			(end -0.674878 -1.124966)
			(stroke
				(width 0.1)
				(type default)
			)
			(layer "F.Fab")
		)
		(fp_line
			(start 0.674878 1.124966)
			(end 0.674878 -1.124966)
			(stroke
				(width 0.1)
				(type default)
			)
			(layer "F.Fab")
		)
		(fp_poly
			(pts
				(xy -1.447038 -0.760476) (xy -2.052066 -0.457962) (xy -2.052066 -1.06299)
			)
			(stroke
				(width 0)
				(type default)
			)
			(fill yes)
			(layer "F.Fab")
		)
		(pad "1" smd rect
			(at -0.899922 -0.750062)
			(size 0.6096 0.6096)
			(layers "F.Cu" "F.Mask" "F.Paste")
			(net "PWRGD_P3V3_SSD1_R")
		)
		(pad "2" smd rect
			(at -0.899922 0 90)
			(size 0.4064 0.6096)
			(layers "F.Cu" "F.Mask" "F.Paste")
			(net "RST_SMB_SSD1_N")
		)
		(pad "3" smd rect
			(at -0.899922 0.750062)
			(size 0.6096 0.6096)
			(layers "F.Cu" "F.Mask" "F.Paste")
			(net "GND")
		)
		(pad "4" smd rect
			(at 0.899922 0.750062)
			(size 0.6096 0.6096)
			(layers "F.Cu" "F.Mask" "F.Paste")
			(net "RST_SMB_SSD1_ISO_N")
		)
		(pad "5" smd rect
			(at 0.899922 -0.750062)
			(size 0.6096 0.6096)
			(layers "F.Cu" "F.Mask" "F.Paste")
			(net "P3V3_AUX")
		)
	)
)
